# T6G (Grand Teton) — schematic netlist excerpt (pin names and nets, part order shuffled) for the footprints in the layout excerpt that follows; sources: Cadence DE-HDL packaged netlist, KiCad conversion of 04192023_DAF0TMB3IC0_F0TG_MB_C_brd_V02_OCP.brd

PR196  Q_RES  8.87K 1% EMPTY  pkg 0402LF  page 212 : A = GND ; B = PVDDCR_CPU0_P1_LSET4
C6518  Q_CAP_DIFFBUS  DIFF BUS_0.22UF 6.3V 20% X6S  pkg C0201  page 275 : \1\ = P5E_CPU0_P0_TX_BUF_C_DN<8> ; \2\ = P5E_CPU0_P0_TX_BUF_DN<8>
R4133  Q_RES  54.9K 1% EMPTY  pkg 0402LF  page 125 : A = P3V3_AUX ; B = GPU_3V3IO_RSVD5_FFU

(kicad_pcb
	(version 20260206)
	(generator "pcbnew")
	(generator_version "10.0")
	(general
		(thickness 1.6)
		(legacy_teardrops no)
	)
	(paper "A4")
	(title_block
		(title "04192023_DAF0TMB3IC0_F0TG_MB_C_brd_V02_OCP.brd")
		(comment 1 "Grand Teton / footprints 4833-4835 of 8354")
	)
	(layers
		(0 "F.Cu" signal "TOP")
		(4 "In1.Cu" signal "GND")
		(6 "In2.Cu" signal "IN1")
		(8 "In3.Cu" signal "GND1")
		(10 "In4.Cu" signal "IN2")
		(12 "In5.Cu" signal "GND2")
		(14 "In6.Cu" signal "IN3")
		(16 "In7.Cu" signal "GND3")
		(18 "In8.Cu" signal "VCC")
		(20 "In9.Cu" signal "VCC1")
		(22 "In10.Cu" signal "GND4")
		(24 "In11.Cu" signal "IN4")
		(26 "In12.Cu" signal "GND5")
		(28 "In13.Cu" signal "IN5")
		(30 "In14.Cu" signal "GND6")
		(32 "In15.Cu" signal "IN6")
		(34 "In16.Cu" signal "GND7")
		(2 "B.Cu" signal "BOTTOM")
		(9 "F.Adhes" user "F.Adhesive")
		(11 "B.Adhes" user "B.Adhesive")
		(13 "F.Paste" user "Package Geometry/Pastemask Top")
		(15 "B.Paste" user "Package Geometry/Pastemask Bottom")
		(5 "F.SilkS" user "Ref Des/Silkscreen Top")
		(7 "B.SilkS" user "Ref Des/Silkscreen Bottom")
		(1 "F.Mask" user "Board Geometry/Soldermask Top")
		(3 "B.Mask" user "Board Geometry/Soldermask Bottom")
		(17 "Dwgs.User" user "User.Drawings")
		(19 "Cmts.User" user "User.Comments")
		(21 "Eco1.User" user "User.Eco1")
		(23 "Eco2.User" user "User.Eco2")
		(25 "Edge.Cuts" user "Board Geometry/Outline")
		(27 "Margin" user)
		(31 "F.CrtYd" user "Package Geometry/Place Bound Top")
		(29 "B.CrtYd" user "Package Geometry/Place Bound Bottom")
		(35 "F.Fab" user "Ref Des/Assembly Top")
		(33 "B.Fab" user "Ref Des/Assembly Bottom")
	)
	(footprint ""
		(layer "F.Cu")
		(at 307.404516 -437.498744 90)
		(property "Reference" "R4133"
			(at 0 0 90)
			(layer "F.SilkS")
			(hide yes)
			(effects
				(font
					(size 1.27 1.27)
				)
			)
		)
		(property "Value" ""
			(at 0 0 90)
			(layer "F.Fab")
			(effects
				(font
					(size 1.27 1.27)
				)
			)
		)
		(duplicate_pad_numbers_are_jumpers no)
		(fp_line
			(start 0.7874 -0.4064)
			(end 0.7874 0.4064)
			(stroke
				(width 0.1524)
				(type default)
			)
			(layer "F.SilkS")
		)
		(fp_line
			(start -0.7874 -0.4064)
			(end 0.7874 -0.4064)
			(stroke
				(width 0.1524)
				(type default)
			)
			(layer "F.SilkS")
		)
		(fp_line
			(start 0.7874 0.4064)
			(end -0.7874 0.4064)
			(stroke
				(width 0.1524)
				(type default)
			)
			(layer "F.SilkS")
		)
		(fp_line
			(start -0.7874 0.4064)
			(end -0.7874 -0.4064)
			(stroke
				(width 0.1524)
				(type default)
			)
			(layer "F.SilkS")
		)
		(fp_line
			(start -0.12065 -0.305054)
			(end -0.12065 -0.2794)
			(stroke
				(width 0.1)
				(type default)
			)
			(layer "F.Fab")
		)
		(fp_line
			(start -0.67945 -0.305054)
			(end -0.12065 -0.305054)
			(stroke
				(width 0.1)
				(type default)
			)
			(layer "F.Fab")
		)
		(fp_line
			(start 0.67945 -0.3048)
			(end 0.67945 0.3048)
			(stroke
				(width 0.1)
				(type default)
			)
			(layer "F.Fab")
		)
		(fp_line
			(start 0.12065 -0.3048)
			(end 0.67945 -0.3048)
			(stroke
				(width 0.1)
				(type default)
			)
			(layer "F.Fab")
		)
		(fp_line
			(start 0.12065 -0.2794)
			(end 0.12065 -0.3048)
			(stroke
				(width 0.1)
				(type default)
			)
			(layer "F.Fab")
		)
		(fp_line
			(start -0.12065 -0.2794)
			(end 0.12065 -0.2794)
			(stroke
				(width 0.1)
				(type default)
			)
			(layer "F.Fab")
		)
		(fp_line
			(start 0.120396 0.2794)
			(end -0.12065 0.2794)
			(stroke
				(width 0.1)
				(type default)
			)
			(layer "F.Fab")
		)
		(fp_line
			(start -0.12065 0.2794)
			(end -0.12065 0.3048)
			(stroke
				(width 0.1)
				(type default)
			)
			(layer "F.Fab")
		)
		(fp_line
			(start 0.67945 0.3048)
			(end 0.120396 0.3048)
			(stroke
				(width 0.1)
				(type default)
			)
			(layer "F.Fab")
		)
		(fp_line
			(start 0.120396 0.3048)
			(end 0.120396 0.2794)
			(stroke
				(width 0.1)
				(type default)
			)
			(layer "F.Fab")
		)
		(fp_line
			(start -0.12065 0.3048)
			(end -0.67945 0.3048)
			(stroke
				(width 0.1)
				(type default)
			)
			(layer "F.Fab")
		)
		(fp_line
			(start -0.67945 0.3048)
			(end -0.67945 -0.305054)
			(stroke
				(width 0.1)
				(type default)
			)
			(layer "F.Fab")
		)
		(pad "1" smd circle
			(at -0.40005 0 90)
			(size 0 0)
			(layers "F.Cu" "F.Mask" "F.Paste")
			(net "P3V3_AUX")
		)
		(pad "2" smd circle
			(at 0.40005 0 90)
			(size 0 0)
			(layers "F.Cu" "F.Mask" "F.Paste")
			(net "GPU_3V3IO_RSVD5_FFU")
		)
	)
	(footprint ""
		(layer "F.Cu")
		(at 108.760514 -172.960284)
		(property "Reference" "PR196"
			(at 0 0 0)
			(layer "F.SilkS")
			(hide yes)
			(effects
				(font
					(size 1.27 1.27)
				)
			)
		)
		(property "Value" ""
			(at 0 0 0)
			(layer "F.Fab")
			(effects
				(font
					(size 1.27 1.27)
				)
			)
		)
		(duplicate_pad_numbers_are_jumpers no)
		(fp_line
			(start -0.7874 -0.4064)
			(end 0.7874 -0.4064)
			(stroke
				(width 0.1524)
				(type default)
			)
			(layer "F.SilkS")
		)
		(fp_line
			(start -0.7874 0.4064)
			(end -0.7874 -0.4064)
			(stroke
				(width 0.1524)
				(type default)
			)
			(layer "F.SilkS")
		)
		(fp_line
			(start 0.7874 -0.4064)
			(end 0.7874 0.4064)
			(stroke
				(width 0.1524)
				(type default)
			)
			(layer "F.SilkS")
		)
		(fp_line
			(start 0.7874 0.4064)
			(end -0.7874 0.4064)
			(stroke
				(width 0.1524)
				(type default)
			)
			(layer "F.SilkS")
		)
		(fp_line
			(start -0.67945 -0.305054)
			(end -0.12065 -0.305054)
			(stroke
				(width 0.1)
				(type default)
			)
			(layer "F.Fab")
		)
		(fp_line
			(start -0.67945 0.3048)
			(end -0.67945 -0.305054)
			(stroke
				(width 0.1)
				(type default)
			)
			(layer "F.Fab")
		)
		(fp_line
			(start -0.12065 -0.305054)
			(end -0.12065 -0.2794)
			(stroke
				(width 0.1)
				(type default)
			)
			(layer "F.Fab")
		)
		(fp_line
			(start -0.12065 -0.2794)
			(end 0.12065 -0.2794)
			(stroke
				(width 0.1)
				(type default)
			)
			(layer "F.Fab")
		)
		(fp_line
			(start -0.12065 0.2794)
			(end -0.12065 0.3048)
			(stroke
				(width 0.1)
				(type default)
			)
			(layer "F.Fab")
		)
		(fp_line
			(start -0.12065 0.3048)
			(end -0.67945 0.3048)
			(stroke
				(width 0.1)
				(type default)
			)
			(layer "F.Fab")
		)
		(fp_line
			(start 0.120396 0.2794)
			(end -0.12065 0.2794)
			(stroke
				(width 0.1)
				(type default)
			)
			(layer "F.Fab")
		)
		(fp_line
			(start 0.120396 0.3048)
			(end 0.120396 0.2794)
			(stroke
				(width 0.1)
				(type default)
			)
			(layer "F.Fab")
		)
		(fp_line
			(start 0.12065 -0.3048)
			(end 0.67945 -0.3048)
			(stroke
				(width 0.1)
				(type default)
			)
			(layer "F.Fab")
		)
		(fp_line
			(start 0.12065 -0.2794)
			(end 0.12065 -0.3048)
			(stroke
				(width 0.1)
				(type default)
			)
			(layer "F.Fab")
		)
		(fp_line
			(start 0.67945 -0.3048)
			(end 0.67945 0.3048)
			(stroke
				(width 0.1)
				(type default)
			)
			(layer "F.Fab")
		)
		(fp_line
			(start 0.67945 0.3048)
			(end 0.120396 0.3048)
			(stroke
				(width 0.1)
				(type default)
			)
			(layer "F.Fab")
		)
		(pad "1" smd circle
			(at -0.40005 0)
			(size 0 0)
			(layers "F.Cu" "F.Mask" "F.Paste")
			(net "GND")
		)
		(pad "2" smd circle
			(at 0.40005 0)
			(size 0 0)
			(layers "F.Cu" "F.Mask" "F.Paste")
			(net "PVDDCR_CPU0_P1_LSET4")
		)
	)
	(footprint ""
		(layer "F.Cu")
		(at 328.274426 -416.899344 -90)
		(property "Reference" "C6518"
			(at 0 0 270)
			(layer "F.SilkS")
			(hide yes)
			(effects
				(font
					(size 1.27 1.27)
				)
			)
		)
		(property "Value" ""
			(at 0 0 270)
			(layer "F.Fab")
			(effects
				(font
					(size 1.27 1.27)
				)
			)
		)
		(duplicate_pad_numbers_are_jumpers no)
		(fp_line
			(start -0.299974 0.150114)
			(end -0.299974 -0.150114)
			(stroke
				(width 0.1)
				(type default)
			)
			(layer "F.Fab")
		)
		(fp_line
			(start 0.299974 0.150114)
			(end -0.299974 0.150114)
			(stroke
				(width 0.1)
				(type default)
			)
			(layer "F.Fab")
		)
		(fp_line
			(start -0.299974 -0.150114)
			(end 0.299974 -0.150114)
			(stroke
				(width 0.1)
				(type default)
			)
			(layer "F.Fab")
		)
		(fp_line
			(start 0.299974 -0.150114)
			(end 0.299974 0.150114)
			(stroke
				(width 0.1)
				(type default)
			)
			(layer "F.Fab")
		)
		(pad "1" smd rect
			(at -0.2667 0 270)
			(size 0.3048 0.381)
			(layers "F.Cu" "F.Mask" "F.Paste")
			(net "P5E_CPU0_P0_TX_BUF_C_DN<8>")
		)
		(pad "2" smd rect
			(at 0.2667 0 270)
			(size 0.3048 0.381)
			(layers "F.Cu" "F.Mask" "F.Paste")
			(net "P5E_CPU0_P0_TX_BUF_DN<8>")
		)
	)
)
